FILE_TYPE = CONNECTIVITY;
{Allegro Design Entry HDL 17.4-2019 S026 (4007227) 1/17/2022}
"PAGE_NUMBER" = 62;
0"NC";
END.
